# TIMECARD (Time Appliance Project (Time Card)) — schematic netlist excerpt (pin names and nets, part order shuffled) for the footprints in the layout excerpt that follows; sources: Cadence DE-HDL packaged netlist, KiCad conversion of R4006-B0001-02_R01.brd

U28  ICP_10100_LGA10  ICP-10100  pkg LGA10_079_P0197  page 19
  RESV_1  = UNNAMED_8_ICP10100LGA10_I24_RES
  SCL  = R_ICP10100_I2C_SCL
  RESV_2  = UNNAMED_8_ICP10100LGA10_I24_R_1
  SDA  = R_ICP10100_I2C_SDA
  RESV_3  = UNNAMED_8_ICP10100LGA10_I24_R_2
  RESV_4  = UNNAMED_8_ICP10100LGA10_I24_R_3
  RESV_5  = UNNAMED_8_ICP10100LGA10_I24_R_4
  GND_1  = SG
  GND_2  = SG
  VDD  = XP1R8V_ICP10100

(kicad_pcb
	(version 20260206)
	(generator "pcbnew")
	(generator_version "10.0")
	(general
		(thickness 1.6)
		(legacy_teardrops no)
	)
	(paper "A4")
	(title_block
		(title "timecard-production-celestica-r4006 — R4006-B0001-02_R01.brd")
		(comment 1 "Time Appliance Project (Time Card) / footprints 133-133 of 1113")
	)
	(layers
		(0 "F.Cu" signal "TOP")
		(4 "In1.Cu" signal "L02_GND1")
		(6 "In2.Cu" signal "L03_SIG1")
		(8 "In3.Cu" signal "L04_GND2")
		(10 "In4.Cu" signal "L05_VCC1")
		(12 "In5.Cu" signal "L06_VCC2")
		(14 "In6.Cu" signal "L07_GND3")
		(16 "In7.Cu" signal "L08_SIG2")
		(18 "In8.Cu" signal "L09_GND4")
		(2 "B.Cu" signal "BOTTOM")
		(9 "F.Adhes" user "F.Adhesive")
		(11 "B.Adhes" user "B.Adhesive")
		(13 "F.Paste" user "Package Geometry/Pastemask Top")
		(15 "B.Paste" user "Package Geometry/Pastemask Bottom")
		(5 "F.SilkS" user "Ref Des/Silkscreen Top")
		(7 "B.SilkS" user "Ref Des/Silkscreen Bottom")
		(1 "F.Mask" user "Board Geometry/Soldermask Top")
		(3 "B.Mask" user "Board Geometry/Soldermask Bottom")
		(17 "Dwgs.User" user "User.Drawings")
		(19 "Cmts.User" user "User.Comments")
		(21 "Eco1.User" user "User.Eco1")
		(23 "Eco2.User" user "User.Eco2")
		(25 "Edge.Cuts" user "Board Geometry/Outline")
		(27 "Margin" user)
		(31 "F.CrtYd" user "Package Geometry/Place Bound Top")
		(29 "B.CrtYd" user "Package Geometry/Place Bound Bottom")
		(35 "F.Fab" user "Ref Des/Assembly Top")
		(33 "B.Fab" user "Ref Des/Assembly Bottom")
	)
	(footprint ""
		(layer "F.Cu")
		(at 20.052792 -67.5894 180)
		(property "Reference" "U28"
			(at 0.494792 2.09423 0)
			(unlocked yes)
			(layer "F.SilkS")
			(effects
				(font
					(size 0.7874 0.5842)
					(thickness 0.1524)
				)
			)
		)
		(property "Value" ""
			(at 0 0 180)
			(layer "F.Fab")
			(effects
				(font
					(size 1.27 1.27)
				)
			)
		)
		(property "Device Type" "ICP_10100_LGA10-A222-00002-FB,A"
			(at 0.0635 3.182112 180)
			(unlocked yes)
			(layer "F.Fab")
			(hide yes)
			(effects
				(font
					(size 0.7874 0.5842)
					(thickness 0.1524)
				)
			)
		)
		(property "User Part Number" "PARTNUM*"
			(at 0.0635 4.375912 180)
			(unlocked yes)
			(layer "Cmts.User")
			(hide yes)
			(effects
				(font
					(size 0.7874 0.5842)
					(thickness 0.1524)
				)
			)
		)
		(duplicate_pad_numbers_are_jumpers no)
		(fp_line
			(start 1.304036 1.304036)
			(end -1.304036 1.304036)
			(stroke
				(width 0.1)
				(type default)
			)
			(layer "F.SilkS")
		)
		(fp_line
			(start 1.304036 -1.304036)
			(end 1.304036 1.304036)
			(stroke
				(width 0.1)
				(type default)
			)
			(layer "F.SilkS")
		)
		(fp_line
			(start -1.304036 1.304036)
			(end -1.304036 -1.304036)
			(stroke
				(width 0.1)
				(type default)
			)
			(layer "F.SilkS")
		)
		(fp_line
			(start -1.304036 -1.304036)
			(end 1.304036 -1.304036)
			(stroke
				(width 0.1)
				(type default)
			)
			(layer "F.SilkS")
		)
		(fp_poly
			(pts
				(arc
					(start -2.172208 2.2606)
					(mid -1.156716 2.2606)
					(end -2.172208 2.2606)
				)
			)
			(stroke
				(width 0)
				(type default)
			)
			(fill yes)
			(layer "F.SilkS")
		)
		(fp_rect
			(start 1.558036 1.558036)
			(end -1.558036 -1.558036)
			(stroke
				(width 0)
				(type default)
			)
			(fill no)
			(layer "F.CrtYd")
		)
		(fp_line
			(start 1.050036 1.050036)
			(end -1.050036 1.050036)
			(stroke
				(width 0.1)
				(type default)
			)
			(layer "F.Fab")
		)
		(fp_line
			(start 1.050036 -1.050036)
			(end 1.050036 1.050036)
			(stroke
				(width 0.1)
				(type default)
			)
			(layer "F.Fab")
		)
		(fp_line
			(start -1.050036 1.050036)
			(end -1.050036 -1.050036)
			(stroke
				(width 0.1)
				(type default)
			)
			(layer "F.Fab")
		)
		(fp_line
			(start -1.050036 -1.050036)
			(end 1.050036 -1.050036)
			(stroke
				(width 0.1)
				(type default)
			)
			(layer "F.Fab")
		)
		(fp_poly
			(pts
				(arc
					(start -1.200658 2.133854)
					(mid -0.185166 2.133854)
					(end -1.200658 2.133854)
				)
			)
			(stroke
				(width 0)
				(type default)
			)
			(fill yes)
			(layer "F.Fab")
		)
		(fp_text user "2"
			(at 1.891792 2.10185 0)
			(unlocked yes)
			(layer "F.SilkS")
			(effects
				(font
					(size 0.635 0.4064)
					(thickness 0.1524)
				)
			)
		)
		(fp_text user "5"
			(at 1.759458 -0.96139 0)
			(unlocked yes)
			(layer "F.SilkS")
			(effects
				(font
					(size 0.635 0.4064)
					(thickness 0.1524)
				)
			)
		)
		(fp_text user "3"
			(at 1.693418 0.212598 0)
			(unlocked yes)
			(layer "F.SilkS")
			(effects
				(font
					(size 0.635 0.4064)
					(thickness 0.1524)
				)
			)
		)
		(fp_text user "6"
			(at 1.510792 -1.83515 0)
			(unlocked yes)
			(layer "F.SilkS")
			(effects
				(font
					(size 0.635 0.4064)
					(thickness 0.1524)
				)
			)
		)
		(fp_text user "8"
			(at -1.918208 -1.45415 0)
			(unlocked yes)
			(layer "F.SilkS")
			(effects
				(font
					(size 0.635 0.4064)
					(thickness 0.1524)
				)
			)
		)
		(fp_text user "3"
			(at 1.637792 1.09093 0)
			(unlocked yes)
			(layer "F.Fab")
			(effects
				(font
					(size 0.7874 0.5842)
					(thickness 0.1524)
				)
			)
		)
		(fp_text user "5"
			(at 1.383792 -0.56007 0)
			(unlocked yes)
			(layer "F.Fab")
			(effects
				(font
					(size 0.7874 0.5842)
					(thickness 0.1524)
				)
			)
		)
		(fp_text user "6"
			(at 1.383792 -1.70307 0)
			(unlocked yes)
			(layer "F.Fab")
			(effects
				(font
					(size 0.7874 0.5842)
					(thickness 0.1524)
				)
			)
		)
		(fp_text user "2"
			(at 0.621792 1.72593 0)
			(unlocked yes)
			(layer "F.Fab")
			(effects
				(font
					(size 0.7874 0.5842)
					(thickness 0.1524)
				)
			)
		)
		(fp_text user "7"
			(at -0.521208 -1.70307 0)
			(unlocked yes)
			(layer "F.Fab")
			(effects
				(font
					(size 0.7874 0.5842)
					(thickness 0.1524)
				)
			)
		)
		(fp_text user "8"
			(at -1.664208 -0.68707 0)
			(unlocked yes)
			(layer "F.Fab")
			(effects
				(font
					(size 0.7874 0.5842)
					(thickness 0.1524)
				)
			)
		)
		(fp_text user "10"
			(at -1.791208 1.47193 0)
			(unlocked yes)
			(layer "F.Fab")
			(effects
				(font
					(size 0.7874 0.5842)
					(thickness 0.1524)
				)
			)
		)
		(pad "1" smd rect
			(at -0.249936 0.774954 180)
			(size 0.2794 0.3556)
			(layers "F.Cu" "F.Mask" "F.Paste")
			(net "UNNAMED_8_ICP10100LGA10_I24_RES")
		)
		(pad "2" smd rect
			(at 0.249936 0.774954 180)
			(size 0.2794 0.3556)
			(layers "F.Cu" "F.Mask" "F.Paste")
			(net "R_ICP10100_I2C_SCL")
		)
		(pad "3" smd rect
			(at 0.774954 0.500126 180)
			(size 0.3556 0.2794)
			(layers "F.Cu" "F.Mask" "F.Paste")
			(net "UNNAMED_8_ICP10100LGA10_I24_R_1")
		)
		(pad "4" smd rect
			(at 0.774954 0 180)
			(size 0.3556 0.2794)
			(layers "F.Cu" "F.Mask" "F.Paste")
			(net "R_ICP10100_I2C_SDA")
		)
		(pad "5" smd rect
			(at 0.774954 -0.500126 180)
			(size 0.3556 0.2794)
			(layers "F.Cu" "F.Mask" "F.Paste")
			(net "UNNAMED_8_ICP10100LGA10_I24_R_2")
		)
		(pad "6" smd rect
			(at 0.249936 -0.774954 180)
			(size 0.2794 0.3556)
			(layers "F.Cu" "F.Mask" "F.Paste")
			(net "UNNAMED_8_ICP10100LGA10_I24_R_3")
		)
		(pad "7" smd rect
			(at -0.249936 -0.774954 180)
			(size 0.2794 0.3556)
			(layers "F.Cu" "F.Mask" "F.Paste")
			(net "UNNAMED_8_ICP10100LGA10_I24_R_4")
		)
		(pad "8" smd rect
			(at -0.774954 -0.500126 180)
			(size 0.3556 0.2794)
			(layers "F.Cu" "F.Mask" "F.Paste")
			(net "SG")
		)
		(pad "9" smd rect
			(at -0.774954 0 180)
			(size 0.3556 0.2794)
			(layers "F.Cu" "F.Mask" "F.Paste")
			(net "SG")
		)
		(pad "10" smd rect
			(at -0.774954 0.500126 180)
			(size 0.3556 0.2794)
			(layers "F.Cu" "F.Mask" "F.Paste")
			(net "XP1R8V_ICP10100")
		)
	)
)
